(kicad_pcb
	(version 20260206)
	(generator "pcbnew")
	(generator_version "10.0")
	(general
		(thickness 1.6)
		(legacy_teardrops no)
	)
	(paper "A4")
	(title_block
		(title "Bryce Canyon_SCC_16316-1_OCP.brd")
		(comment 1 "Bryce Canyon / footprints 277-282 of 1561")
	)
	(layers
		(0 "F.Cu" signal "TOP")
		(4 "In1.Cu" signal "L2GND")
		(6 "In2.Cu" signal "L3")
		(8 "In3.Cu" signal "L4VCC")
		(10 "In4.Cu" signal "L5VCC")
		(12 "In5.Cu" signal "L6")
		(14 "In6.Cu" signal "L7GND")
		(2 "B.Cu" signal "BOTTOM")
		(9 "F.Adhes" user "F.Adhesive")
		(11 "B.Adhes" user "B.Adhesive")
		(13 "F.Paste" user "Package Geometry/Pastemask Top")
		(15 "B.Paste" user "Package Geometry/Pastemask Bottom")
		(5 "F.SilkS" user "Ref Des/Silkscreen Top")
		(7 "B.SilkS" user "Ref Des/Silkscreen Bottom")
		(1 "F.Mask" user "Board Geometry/Soldermask Top")
		(3 "B.Mask" user "Board Geometry/Soldermask Bottom")
		(17 "Dwgs.User" user "User.Drawings")
		(19 "Cmts.User" user "User.Comments")
		(21 "Eco1.User" user "User.Eco1")
		(23 "Eco2.User" user "User.Eco2")
		(25 "Edge.Cuts" user "Board Geometry/Outline")
		(27 "Margin" user)
		(31 "F.CrtYd" user "Package Geometry/Place Bound Top")
		(29 "B.CrtYd" user "Package Geometry/Place Bound Bottom")
		(35 "F.Fab" user "Ref Des/Assembly Top")
		(33 "B.Fab" user "Ref Des/Assembly Bottom")
	)
	(footprint ""
		(layer "F.Cu")
		(at 69.139308 -16.9291 90)
		(property "Reference" "U14"
			(at 0 0 90)
			(layer "F.SilkS")
			(hide yes)
			(effects
				(font
					(size 1.27 1.27)
				)
			)
		)
		(property "Value" "SNLVC8T245DGVR-GP"
			(at 0 -11.1252 90)
			(unlocked yes)
			(layer "F.Fab")
			(hide yes)
			(effects
				(font
					(size 1.016 1.016)
					(thickness 0.1524)
				)
			)
		)
		(property "Device Type" "TVSOP24H48"
			(at 0 -12.6492 90)
			(unlocked yes)
			(layer "F.Fab")
			(hide yes)
			(effects
				(font
					(size 1.016 1.016)
					(thickness 0.1524)
				)
			)
		)
		(duplicate_pad_numbers_are_jumpers no)
		(fp_line
			(start 2.2987 -1.397)
			(end -2.9337 -1.397)
			(stroke
				(width 0.1524)
				(type default)
			)
			(layer "F.SilkS")
		)
		(fp_line
			(start -2.9337 -1.397)
			(end -2.9337 1.397)
			(stroke
				(width 0.1524)
				(type default)
			)
			(layer "F.SilkS")
		)
		(fp_line
			(start -2.9337 -0.3683)
			(end -2.5654 0)
			(stroke
				(width 0.1524)
				(type default)
			)
			(layer "F.SilkS")
		)
		(fp_line
			(start -2.5654 0)
			(end -2.9337 0.3683)
			(stroke
				(width 0.1524)
				(type default)
			)
			(layer "F.SilkS")
		)
		(fp_line
			(start 2.2987 1.397)
			(end 2.2987 -1.397)
			(stroke
				(width 0.1524)
				(type default)
			)
			(layer "F.SilkS")
		)
		(fp_line
			(start -2.7559 1.397)
			(end -2.7559 3.8354)
			(stroke
				(width 0.508)
				(type default)
			)
			(layer "F.SilkS")
		)
		(fp_line
			(start -2.9337 1.397)
			(end 2.2987 1.397)
			(stroke
				(width 0.1524)
				(type default)
			)
			(layer "F.SilkS")
		)
		(fp_rect
			(start -3.0099 4.0894)
			(end 3.0099 -4.0894)
			(stroke
				(width 0)
				(type default)
			)
			(fill no)
			(layer "F.CrtYd")
		)
		(fp_poly
			(pts
				(xy -3.0099 -4.0894) (xy 3.0099 -4.0894) (xy 3.0099 4.0894) (xy -3.0099 4.0894)
			)
			(stroke
				(width 0)
				(type default)
			)
			(fill no)
			(layer "F.Fab")
		)
		(pad "1" smd rect
			(at -2.19964 2.8194 90)
			(size 0.2032 1.524)
			(layers "F.Cu" "F.Mask" "F.Paste")
			(net "P3V3")
		)
		(pad "2" smd rect
			(at -1.79959 2.8194 90)
			(size 0.2032 1.524)
			(layers "F.Cu" "F.Mask" "F.Paste")
			(net "GND")
		)
		(pad "3" smd rect
			(at -1.39954 2.8194 90)
			(size 0.2032 1.524)
			(layers "F.Cu" "F.Mask" "F.Paste")
			(net "SCC_LOC_HEARTBEAT")
		)
		(pad "4" smd rect
			(at -0.99949 2.8194 90)
			(size 0.2032 1.524)
			(layers "F.Cu" "F.Mask" "F.Paste")
			(net "PWM_OUT_ZONE_C")
		)
		(pad "5" smd rect
			(at -0.59944 2.8194 90)
			(size 0.2032 1.524)
			(layers "F.Cu" "F.Mask" "F.Paste")
			(net "PWM_OUT_ZONE_D")
		)
		(pad "6" smd rect
			(at -0.19939 2.8194 90)
			(size 0.2032 1.524)
			(layers "F.Cu" "F.Mask" "F.Paste")
			(net "SYS_PWR_LED_N")
		)
		(pad "7" smd rect
			(at 0.19939 2.8194 90)
			(size 0.2032 1.524)
			(layers "F.Cu" "F.Mask" "F.Paste")
			(net "ENCL_FAULT_LED")
		)
		(pad "8" smd rect
			(at 0.59944 2.8194 90)
			(size 0.2032 1.524)
			(layers "F.Cu" "F.Mask" "F.Paste")
			(net "BMC_SPARE_1")
		)
		(pad "9" smd rect
			(at 0.99949 2.8194 90)
			(size 0.2032 1.524)
			(layers "F.Cu" "F.Mask" "F.Paste")
			(net "Net_36")
		)
		(pad "10" smd rect
			(at 1.39954 2.8194 90)
			(size 0.2032 1.524)
			(layers "F.Cu" "F.Mask" "F.Paste")
			(net "Net_38")
		)
		(pad "11" smd rect
			(at 1.79959 2.8194 90)
			(size 0.2032 1.524)
			(layers "F.Cu" "F.Mask" "F.Paste")
			(net "GND")
		)
		(pad "12" smd rect
			(at 2.19964 2.8194 90)
			(size 0.2032 1.524)
			(layers "F.Cu" "F.Mask" "F.Paste")
			(net "GND")
		)
		(pad "13" smd rect
			(at 2.19964 -2.8194 90)
			(size 0.2032 1.524)
			(layers "F.Cu" "F.Mask" "F.Paste")
			(net "GND")
		)
		(pad "14" smd rect
			(at 1.79959 -2.8194 90)
			(size 0.2032 1.524)
			(layers "F.Cu" "F.Mask" "F.Paste")
			(net "Net_39")
		)
		(pad "15" smd rect
			(at 1.39954 -2.8194 90)
			(size 0.2032 1.524)
			(layers "F.Cu" "F.Mask" "F.Paste")
			(net "Net_37")
		)
		(pad "16" smd rect
			(at 0.99949 -2.8194 90)
			(size 0.2032 1.524)
			(layers "F.Cu" "F.Mask" "F.Paste")
			(net "BMC_SPARE_1_LS")
		)
		(pad "17" smd rect
			(at 0.59944 -2.8194 90)
			(size 0.2032 1.524)
			(layers "F.Cu" "F.Mask" "F.Paste")
			(net "ENCL_FAULT_LED_LS")
		)
		(pad "18" smd rect
			(at 0.19939 -2.8194 90)
			(size 0.2032 1.524)
			(layers "F.Cu" "F.Mask" "F.Paste")
			(net "SYS_PWR_LED_LS_N")
		)
		(pad "19" smd rect
			(at -0.19939 -2.8194 90)
			(size 0.2032 1.524)
			(layers "F.Cu" "F.Mask" "F.Paste")
			(net "PWM_OUT_ZONE_D_LS")
		)
		(pad "20" smd rect
			(at -0.59944 -2.8194 90)
			(size 0.2032 1.524)
			(layers "F.Cu" "F.Mask" "F.Paste")
			(net "PWM_OUT_ZONE_C_LS")
		)
		(pad "21" smd rect
			(at -0.99949 -2.8194 90)
			(size 0.2032 1.524)
			(layers "F.Cu" "F.Mask" "F.Paste")
			(net "SCC_LOC_HEARTBEAT_LS")
		)
		(pad "22" smd rect
			(at -1.39954 -2.8194 90)
			(size 0.2032 1.524)
			(layers "F.Cu" "F.Mask" "F.Paste")
			(net "LS_EN_U14")
		)
		(pad "23" smd rect
			(at -1.79959 -2.8194 90)
			(size 0.2032 1.524)
			(layers "F.Cu" "F.Mask" "F.Paste")
			(net "P1V8_E")
		)
		(pad "24" smd rect
			(at -2.19964 -2.8194 90)
			(size 0.2032 1.524)
			(layers "F.Cu" "F.Mask" "F.Paste")
			(net "P1V8_E")
		)
	)
	(footprint ""
		(layer "F.Cu")
		(at 170.955716 -108.891324)
		(property "Reference" "U9"
			(at 0 0 0)
			(layer "F.SilkS")
			(hide yes)
			(effects
				(font
					(size 1.27 1.27)
				)
			)
		)
		(property "Value" "SN74LVC1G07DCKR-GP"
			(at -2.3368 -8.6868 0)
			(unlocked yes)
			(layer "F.Fab")
			(hide yes)
			(effects
				(font
					(size 1.016 1.016)
					(thickness 0.1524)
				)
			)
		)
		(property "Device Type" "SC70-5H44"
			(at -2.3114 -10.414 0)
			(unlocked yes)
			(layer "F.Fab")
			(hide yes)
			(effects
				(font
					(size 1.016 1.016)
					(thickness 0.1524)
				)
			)
		)
		(duplicate_pad_numbers_are_jumpers no)
		(fp_line
			(start -1.27 -1.7018)
			(end 1.27 -1.7018)
			(stroke
				(width 0.1524)
				(type default)
			)
			(layer "F.SilkS")
		)
		(fp_line
			(start -1.27 1.7018)
			(end -1.27 -1.7018)
			(stroke
				(width 0.1524)
				(type default)
			)
			(layer "F.SilkS")
		)
		(fp_line
			(start 0.6604 -1.8034)
			(end 1.3843 -1.8034)
			(stroke
				(width 0.3302)
				(type default)
			)
			(layer "F.SilkS")
		)
		(fp_line
			(start 1.27 -1.7018)
			(end 1.27 1.7018)
			(stroke
				(width 0.1524)
				(type default)
			)
			(layer "F.SilkS")
		)
		(fp_line
			(start 1.27 1.7018)
			(end -1.27 1.7018)
			(stroke
				(width 0.1524)
				(type default)
			)
			(layer "F.SilkS")
		)
		(fp_line
			(start 1.3843 -1.8034)
			(end 1.3843 -1.1176)
			(stroke
				(width 0.3302)
				(type default)
			)
			(layer "F.SilkS")
		)
		(fp_rect
			(start -1.524 1.9558)
			(end 1.524 -1.9558)
			(stroke
				(width 0)
				(type default)
			)
			(fill no)
			(layer "F.CrtYd")
		)
		(fp_poly
			(pts
				(xy -1.524 -1.9558) (xy 1.524 -1.9558) (xy 1.524 1.9558) (xy -1.524 1.9558)
			)
			(stroke
				(width 0)
				(type default)
			)
			(fill no)
			(layer "F.Fab")
		)
		(pad "1" smd rect
			(at 0.65024 -0.8255)
			(size 0.4064 1.2192)
			(layers "F.Cu" "F.Mask" "F.Paste")
			(net "Net_48")
		)
		(pad "2" smd rect
			(at 0 -0.8255)
			(size 0.4064 1.2192)
			(layers "F.Cu" "F.Mask" "F.Paste")
			(net "P0V975_STAT")
		)
		(pad "3" smd rect
			(at -0.65024 -0.8255)
			(size 0.4064 1.2192)
			(layers "F.Cu" "F.Mask" "F.Paste")
			(net "GND")
		)
		(pad "4" smd rect
			(at -0.65024 0.8255)
			(size 0.4064 1.2192)
			(layers "F.Cu" "F.Mask" "F.Paste")
			(net "SCC_FULL_PGOOD_LS")
		)
		(pad "5" smd rect
			(at 0.65024 0.8255)
			(size 0.4064 1.2192)
			(layers "F.Cu" "F.Mask" "F.Paste")
			(net "P3V3")
		)
	)
	(footprint ""
		(layer "F.Cu")
		(at 10.1854 -100.584 90)
		(property "Reference" "U120"
			(at 0 0 90)
			(layer "F.SilkS")
			(hide yes)
			(effects
				(font
					(size 1.27 1.27)
				)
			)
		)
		(property "Value" "NX3L1G66GW-GP"
			(at -2.3368 -8.6868 90)
			(unlocked yes)
			(layer "F.Fab")
			(hide yes)
			(effects
				(font
					(size 1.016 1.016)
					(thickness 0.1524)
				)
			)
		)
		(property "Device Type" "SC70-5H44"
			(at -2.3114 -10.414 90)
			(unlocked yes)
			(layer "F.Fab")
			(hide yes)
			(effects
				(font
					(size 1.016 1.016)
					(thickness 0.1524)
				)
			)
		)
		(duplicate_pad_numbers_are_jumpers no)
		(fp_line
			(start 1.3843 -1.8034)
			(end 1.3843 -1.1176)
			(stroke
				(width 0.3302)
				(type default)
			)
			(layer "F.SilkS")
		)
		(fp_line
			(start 0.6604 -1.8034)
			(end 1.3843 -1.8034)
			(stroke
				(width 0.3302)
				(type default)
			)
			(layer "F.SilkS")
		)
		(fp_line
			(start 1.27 -1.7018)
			(end 1.27 1.7018)
			(stroke
				(width 0.1524)
				(type default)
			)
			(layer "F.SilkS")
		)
		(fp_line
			(start -1.27 -1.7018)
			(end 1.27 -1.7018)
			(stroke
				(width 0.1524)
				(type default)
			)
			(layer "F.SilkS")
		)
		(fp_line
			(start 1.27 1.7018)
			(end -1.27 1.7018)
			(stroke
				(width 0.1524)
				(type default)
			)
			(layer "F.SilkS")
		)
		(fp_line
			(start -1.27 1.7018)
			(end -1.27 -1.7018)
			(stroke
				(width 0.1524)
				(type default)
			)
			(layer "F.SilkS")
		)
		(fp_rect
			(start -1.524 1.9558)
			(end 1.524 -1.9558)
			(stroke
				(width 0)
				(type default)
			)
			(fill no)
			(layer "F.CrtYd")
		)
		(fp_poly
			(pts
				(xy -1.524 -1.9558) (xy 1.524 -1.9558) (xy 1.524 1.9558) (xy -1.524 1.9558)
			)
			(stroke
				(width 0)
				(type default)
			)
			(fill no)
			(layer "F.Fab")
		)
		(pad "1" smd rect
			(at 0.65024 -0.8255 90)
			(size 0.4064 1.2192)
			(layers "F.Cu" "F.Mask" "F.Paste")
			(net "SCC_FULL_PGOOD")
		)
		(pad "2" smd rect
			(at 0 -0.8255 90)
			(size 0.4064 1.2192)
			(layers "F.Cu" "F.Mask" "F.Paste")
			(net "SCC_FULL_PGOOD_BUF_R")
		)
		(pad "3" smd rect
			(at -0.65024 -0.8255 90)
			(size 0.4064 1.2192)
			(layers "F.Cu" "F.Mask" "F.Paste")
			(net "GND")
		)
		(pad "4" smd rect
			(at -0.65024 0.8255 90)
			(size 0.4064 1.2192)
			(layers "F.Cu" "F.Mask" "F.Paste")
			(net "U120_EN")
		)
		(pad "5" smd rect
			(at 0.65024 0.8255 90)
			(size 0.4064 1.2192)
			(layers "F.Cu" "F.Mask" "F.Paste")
			(net "P3V3")
		)
	)
	(footprint ""
		(layer "F.Cu")
		(at 97.536 -87.0585)
		(property "Reference" "R562"
			(at 0 0 0)
			(layer "F.SilkS")
			(hide yes)
			(effects
				(font
					(size 1.27 1.27)
				)
			)
		)
		(property "Value" "10KR2F-2-GP"
			(at 0.064008 -3.993896 0)
			(unlocked yes)
			(layer "F.Fab")
			(hide yes)
			(effects
				(font
					(size 1.016 1.016)
					(thickness 0.1524)
				)
			)
		)
		(property "Device Type" "R402H16"
			(at 0.064008 -5.517896 0)
			(unlocked yes)
			(layer "F.Fab")
			(hide yes)
			(effects
				(font
					(size 1.016 1.016)
					(thickness 0.1524)
				)
			)
		)
		(duplicate_pad_numbers_are_jumpers no)
		(fp_line
			(start -0.508 -0.9398)
			(end -0.508 0.9398)
			(stroke
				(width 0.1524)
				(type default)
			)
			(layer "F.SilkS")
		)
		(fp_line
			(start 0.508 -0.9398)
			(end -0.508 -0.9398)
			(stroke
				(width 0.1524)
				(type default)
			)
			(layer "F.SilkS")
		)
		(fp_rect
			(start -0.508 0.9398)
			(end 0.508 -0.9398)
			(stroke
				(width 0)
				(type default)
			)
			(fill no)
			(layer "F.CrtYd")
		)
		(fp_rect
			(start -0.508 0.9398)
			(end 0.508 -0.9398)
			(stroke
				(width 0)
				(type default)
			)
			(fill no)
			(layer "F.Fab")
		)
		(pad "1" smd custom
			(at 0 -0.4445)
			(size 0.1397 0.1397)
			(layers "F.Cu" "F.Mask" "F.Paste")
			(net "BMC_RMT_HEARTBEAT_LS")
			(options
				(clearance outline)
				(anchor circle)
			)
			(primitives
				(gr_poly
					(pts
						(arc
							(start -0.1778 -0.2794)
							(mid -0.249642 -0.249642)
							(end -0.2794 -0.1778)
						)
						(arc
							(start -0.2794 0.1778)
							(mid -0.249642 0.249642)
							(end -0.1778 0.2794)
						)
						(arc
							(start 0.1778 0.2794)
							(mid 0.249642 0.249642)
							(end 0.2794 0.1778)
						)
						(arc
							(start 0.2794 -0.1778)
							(mid 0.249642 -0.249642)
							(end 0.1778 -0.2794)
						)
					)
					(width 0)
					(fill yes)
				)
			)
		)
		(pad "2" smd custom
			(at 0 0.4445)
			(size 0.1397 0.1397)
			(layers "F.Cu" "F.Mask" "F.Paste")
			(net "P1V8_E")
			(options
				(clearance outline)
				(anchor circle)
			)
			(primitives
				(gr_poly
					(pts
						(arc
							(start -0.1778 -0.2794)
							(mid -0.249642 -0.249642)
							(end -0.2794 -0.1778)
						)
						(arc
							(start -0.2794 0.1778)
							(mid -0.249642 0.249642)
							(end -0.1778 0.2794)
						)
						(arc
							(start 0.1778 0.2794)
							(mid 0.249642 0.249642)
							(end 0.2794 0.1778)
						)
						(arc
							(start 0.2794 -0.1778)
							(mid 0.249642 -0.249642)
							(end 0.1778 -0.2794)
						)
					)
					(width 0)
					(fill yes)
				)
			)
		)
	)
	(footprint ""
		(layer "F.Cu")
		(at 161.973768 -23.935944 -90)
		(property "Reference" "R170"
			(at 0 0 270)
			(layer "F.SilkS")
			(hide yes)
			(effects
				(font
					(size 1.27 1.27)
				)
			)
		)
		(property "Value" "51R2F-2-GP"
			(at 0.064008 -3.993896 270)
			(unlocked yes)
			(layer "F.Fab")
			(hide yes)
			(effects
				(font
					(size 1.016 1.016)
					(thickness 0.1524)
				)
			)
		)
		(property "Device Type" "R402H16"
			(at 0.064008 -5.517896 270)
			(unlocked yes)
			(layer "F.Fab")
			(hide yes)
			(effects
				(font
					(size 1.016 1.016)
					(thickness 0.1524)
				)
			)
		)
		(duplicate_pad_numbers_are_jumpers no)
		(fp_line
			(start -0.508 -0.9398)
			(end -0.508 0.9398)
			(stroke
				(width 0.1524)
				(type default)
			)
			(layer "F.SilkS")
		)
		(fp_line
			(start 0.508 -0.9398)
			(end -0.508 -0.9398)
			(stroke
				(width 0.1524)
				(type default)
			)
			(layer "F.SilkS")
		)
		(fp_rect
			(start -0.508 0.9398)
			(end 0.508 -0.9398)
			(stroke
				(width 0)
				(type default)
			)
			(fill no)
			(layer "F.CrtYd")
		)
		(fp_rect
			(start -0.508 0.9398)
			(end 0.508 -0.9398)
			(stroke
				(width 0)
				(type default)
			)
			(fill no)
			(layer "F.Fab")
		)
		(pad "1" smd custom
			(at 0 -0.4445 270)
			(size 0.1397 0.1397)
			(layers "F.Cu" "F.Mask" "F.Paste")
			(net "PCIE_CLK_R_P")
			(options
				(clearance outline)
				(anchor circle)
			)
			(primitives
				(gr_poly
					(pts
						(arc
							(start -0.1778 -0.2794)
							(mid -0.249642 -0.249642)
							(end -0.2794 -0.1778)
						)
						(arc
							(start -0.2794 0.1778)
							(mid -0.249642 0.249642)
							(end -0.1778 0.2794)
						)
						(arc
							(start 0.1778 0.2794)
							(mid 0.249642 0.249642)
							(end 0.2794 0.1778)
						)
						(arc
							(start 0.2794 -0.1778)
							(mid 0.249642 -0.249642)
							(end 0.1778 -0.2794)
						)
					)
					(width 0)
					(fill yes)
				)
			)
		)
		(pad "2" smd custom
			(at 0 0.4445 270)
			(size 0.1397 0.1397)
			(layers "F.Cu" "F.Mask" "F.Paste")
			(net "GND")
			(options
				(clearance outline)
				(anchor circle)
			)
			(primitives
				(gr_poly
					(pts
						(arc
							(start -0.1778 -0.2794)
							(mid -0.249642 -0.249642)
							(end -0.2794 -0.1778)
						)
						(arc
							(start -0.2794 0.1778)
							(mid -0.249642 0.249642)
							(end -0.1778 0.2794)
						)
						(arc
							(start 0.1778 0.2794)
							(mid 0.249642 0.249642)
							(end 0.2794 0.1778)
						)
						(arc
							(start 0.2794 -0.1778)
							(mid 0.249642 -0.249642)
							(end 0.1778 -0.2794)
						)
					)
					(width 0)
					(fill yes)
				)
			)
		)
	)
	(footprint ""
		(layer "F.Cu")
		(at 70.0024 -72.6948)
		(property "Reference" "R433"
			(at 0 0 0)
			(layer "F.SilkS")
			(hide yes)
			(effects
				(font
					(size 1.27 1.27)
				)
			)
		)
		(property "Value" "0R2J-2-GP"
			(at 0.064008 -3.993896 0)
			(unlocked yes)
			(layer "F.Fab")
			(hide yes)
			(effects
				(font
					(size 1.016 1.016)
					(thickness 0.1524)
				)
			)
		)
		(property "Device Type" "R402H16"
			(at 0.064008 -5.517896 0)
			(unlocked yes)
			(layer "F.Fab")
			(hide yes)
			(effects
				(font
					(size 1.016 1.016)
					(thickness 0.1524)
				)
			)
		)
		(duplicate_pad_numbers_are_jumpers no)
		(fp_line
			(start -0.508 -0.9398)
			(end -0.508 0.9398)
			(stroke
				(width 0.1524)
				(type default)
			)
			(layer "F.SilkS")
		)
		(fp_line
			(start 0.508 -0.9398)
			(end -0.508 -0.9398)
			(stroke
				(width 0.1524)
				(type default)
			)
			(layer "F.SilkS")
		)
		(fp_rect
			(start -0.508 0.9398)
			(end 0.508 -0.9398)
			(stroke
				(width 0)
				(type default)
			)
			(fill no)
			(layer "F.CrtYd")
		)
		(fp_rect
			(start -0.508 0.9398)
			(end 0.508 -0.9398)
			(stroke
				(width 0)
				(type default)
			)
			(fill no)
			(layer "F.Fab")
		)
		(pad "1" smd custom
			(at 0 -0.4445)
			(size 0.1397 0.1397)
			(layers "F.Cu" "F.Mask" "F.Paste")
			(net "LS_EN_U39")
			(options
				(clearance outline)
				(anchor circle)
			)
			(primitives
				(gr_poly
					(pts
						(arc
							(start -0.1778 -0.2794)
							(mid -0.249642 -0.249642)
							(end -0.2794 -0.1778)
						)
						(arc
							(start -0.2794 0.1778)
							(mid -0.249642 0.249642)
							(end -0.1778 0.2794)
						)
						(arc
							(start 0.1778 0.2794)
							(mid 0.249642 0.249642)
							(end 0.2794 0.1778)
						)
						(arc
							(start 0.2794 -0.1778)
							(mid 0.249642 -0.249642)
							(end 0.1778 -0.2794)
						)
					)
					(width 0)
					(fill yes)
				)
			)
		)
		(pad "2" smd custom
			(at 0 0.4445)
			(size 0.1397 0.1397)
			(layers "F.Cu" "F.Mask" "F.Paste")
			(net "VREF6")
			(options
				(clearance outline)
				(anchor circle)
			)
			(primitives
				(gr_poly
					(pts
						(arc
							(start -0.1778 -0.2794)
							(mid -0.249642 -0.249642)
							(end -0.2794 -0.1778)
						)
						(arc
							(start -0.2794 0.1778)
							(mid -0.249642 0.249642)
							(end -0.1778 0.2794)
						)
						(arc
							(start 0.1778 0.2794)
							(mid 0.249642 0.249642)
							(end 0.2794 0.1778)
						)
						(arc
							(start 0.2794 -0.1778)
							(mid 0.249642 -0.249642)
							(end 0.1778 -0.2794)
						)
					)
					(width 0)
					(fill yes)
				)
			)
		)
	)
)
